(kicad_pcb
	(version 20260206)
	(generator "pcbnew")
	(generator_version "10.0")
	(general
		(thickness 1.6)
		(legacy_teardrops no)
	)
	(paper "A4")
	(title_block
		(title "Wiwynn_Tioga_Pass_MB.brd")
		(comment 1 "Tioga Pass / footprints 3989-3995 of 4770")
	)
	(layers
		(0 "F.Cu" signal "TOP")
		(4 "In1.Cu" signal "L2GND")
		(6 "In2.Cu" signal "L3")
		(8 "In3.Cu" signal "L4GND")
		(10 "In4.Cu" signal "L5")
		(12 "In5.Cu" signal "L6GND")
		(14 "In6.Cu" signal "L7VCC")
		(16 "In7.Cu" signal "L8VCC")
		(18 "In8.Cu" signal "L9GND")
		(20 "In9.Cu" signal "L10")
		(22 "In10.Cu" signal "L11GND")
		(24 "In11.Cu" signal "L12")
		(26 "In12.Cu" signal "L13GND")
		(2 "B.Cu" signal "BOTTOM")
		(9 "F.Adhes" user "F.Adhesive")
		(11 "B.Adhes" user "B.Adhesive")
		(13 "F.Paste" user "Package Geometry/Pastemask Top")
		(15 "B.Paste" user "Package Geometry/Pastemask Bottom")
		(5 "F.SilkS" user "Ref Des/Silkscreen Top")
		(7 "B.SilkS" user "Ref Des/Silkscreen Bottom")
		(1 "F.Mask" user "Board Geometry/Soldermask Top")
		(3 "B.Mask" user "Board Geometry/Soldermask Bottom")
		(17 "Dwgs.User" user "User.Drawings")
		(19 "Cmts.User" user "User.Comments")
		(21 "Eco1.User" user "User.Eco1")
		(23 "Eco2.User" user "User.Eco2")
		(25 "Edge.Cuts" user "Board Geometry/Outline")
		(27 "Margin" user)
		(31 "F.CrtYd" user "Package Geometry/Place Bound Top")
		(29 "B.CrtYd" user "Package Geometry/Place Bound Bottom")
		(35 "F.Fab" user "Ref Des/Assembly Top")
		(33 "B.Fab" user "Ref Des/Assembly Bottom")
	)
	(footprint ""
		(layer "B.Cu")
		(at 437.339232 -152.32507 180)
		(property "Reference" "FB25W3"
			(at 0 0 0)
			(layer "B.SilkS")
			(hide yes)
			(effects
				(font
					(size 1.27 1.27)
				)
				(justify mirror)
			)
		)
		(property "Value" "*"
			(at 0.0127 -7.01675 180)
			(unlocked yes)
			(layer "B.Fab")
			(hide yes)
			(effects
				(font
					(size 0.889 0.889)
					(thickness 0.1524)
				)
				(justify mirror)
			)
		)
		(property "Device Type" "BLM15AG121SN-1GP_DISCRET-G-BLMA"
			(at 0.0127 -8.54075 180)
			(unlocked yes)
			(layer "B.Fab")
			(hide yes)
			(effects
				(font
					(size 0.889 0.889)
					(thickness 0.1524)
				)
				(justify mirror)
			)
		)
		(duplicate_pad_numbers_are_jumpers no)
		(fp_line
			(start 0.508 0.9398)
			(end 0.508 0.8636)
			(stroke
				(width 0.1524)
				(type default)
			)
			(layer "B.SilkS")
		)
		(fp_line
			(start 0.508 -0.9398)
			(end 0.508 0.9398)
			(stroke
				(width 0.1524)
				(type default)
			)
			(layer "B.SilkS")
		)
		(fp_line
			(start -0.508 -0.9398)
			(end 0.508 -0.9398)
			(stroke
				(width 0.1524)
				(type default)
			)
			(layer "B.SilkS")
		)
		(fp_rect
			(start 0.508 0.9398)
			(end -0.508 -0.9398)
			(stroke
				(width 0)
				(type default)
			)
			(fill no)
			(layer "B.CrtYd")
		)
		(fp_rect
			(start 0.508 0.9398)
			(end -0.508 -0.9398)
			(stroke
				(width 0)
				(type default)
			)
			(fill no)
			(layer "B.Fab")
		)
		(pad "1" smd custom
			(at 0 -0.4445)
			(size 0.1397 0.1397)
			(layers "B.Cu" "B.Mask" "B.Paste")
			(net "XDP_TRST_R_N")
			(options
				(clearance outline)
				(anchor circle)
			)
			(primitives
				(gr_poly
					(pts
						(arc
							(start -0.1778 0.2794)
							(mid -0.249642 0.249642)
							(end -0.2794 0.1778)
						)
						(arc
							(start -0.2794 -0.1778)
							(mid -0.249642 -0.249642)
							(end -0.1778 -0.2794)
						)
						(arc
							(start 0.1778 -0.2794)
							(mid 0.249642 -0.249642)
							(end 0.2794 -0.1778)
						)
						(arc
							(start 0.2794 0.1778)
							(mid 0.249642 0.249642)
							(end 0.1778 0.2794)
						)
					)
					(width 0)
					(fill yes)
				)
			)
		)
		(pad "2" smd custom
			(at 0 0.4445)
			(size 0.1397 0.1397)
			(layers "B.Cu" "B.Mask" "B.Paste")
			(net "XDP_TRST_N")
			(options
				(clearance outline)
				(anchor circle)
			)
			(primitives
				(gr_poly
					(pts
						(arc
							(start -0.1778 0.2794)
							(mid -0.249642 0.249642)
							(end -0.2794 0.1778)
						)
						(arc
							(start -0.2794 -0.1778)
							(mid -0.249642 -0.249642)
							(end -0.1778 -0.2794)
						)
						(arc
							(start 0.1778 -0.2794)
							(mid 0.249642 -0.249642)
							(end 0.2794 -0.1778)
						)
						(arc
							(start 0.2794 0.1778)
							(mid 0.249642 0.249642)
							(end 0.1778 0.2794)
						)
					)
					(width 0)
					(fill yes)
				)
			)
		)
	)
	(footprint ""
		(layer "B.Cu")
		(at 17.83842 -106.09072 90)
		(property "Reference" "C9N5"
			(at 0 0 90)
			(layer "B.SilkS")
			(hide yes)
			(effects
				(font
					(size 1.27 1.27)
				)
				(justify mirror)
			)
		)
		(property "Value" ""
			(at 0 0 90)
			(layer "B.Fab")
			(effects
				(font
					(size 1.27 1.27)
				)
				(justify mirror)
			)
		)
		(duplicate_pad_numbers_are_jumpers no)
		(fp_poly
			(pts
				(xy -0.3048 -0.1016) (xy -0.3048 0.9906) (xy 0.3048 0.9906) (xy 0.3048 -0.1016)
			)
			(stroke
				(width 0)
				(type default)
			)
			(fill no)
			(layer "B.CrtYd")
		)
		(fp_line
			(start 0.3048 -0.1016)
			(end 0.3048 0.9906)
			(stroke
				(width 0.1)
				(type default)
			)
			(layer "B.Fab")
		)
		(fp_line
			(start -0.3048 -0.1016)
			(end 0.3048 -0.1016)
			(stroke
				(width 0.1)
				(type default)
			)
			(layer "B.Fab")
		)
		(fp_line
			(start 0.3048 0.9906)
			(end -0.3048 0.9906)
			(stroke
				(width 0.1)
				(type default)
			)
			(layer "B.Fab")
		)
		(fp_line
			(start -0.3048 0.9906)
			(end -0.3048 -0.1016)
			(stroke
				(width 0.1)
				(type default)
			)
			(layer "B.Fab")
		)
		(pad "1" smd rect
			(at 0 0 270)
			(size 0.508 0.508)
			(layers "B.Cu" "B.Mask" "B.Paste")
			(net "P3E_CPU1_PE3_MP_C_TXP<13>")
		)
		(pad "2" smd rect
			(at 0 0.889 270)
			(size 0.508 0.508)
			(layers "B.Cu" "B.Mask" "B.Paste")
			(net "P3E_CPU1_PE3_MP_TXP<13>")
		)
		(zone
			(layer "B.Cu")
			(hatch none 0.5)
			(connect_pads
				(clearance 0)
			)
			(min_thickness 0.25)
			(keepout
				(tracks allowed)
				(vias not_allowed)
				(pads allowed)
				(copperpour not_allowed)
				(footprints allowed)
			)
			(placement
				(enabled no)
				(sheetname "")
			)
			(fill
				(thermal_gap 0.5)
				(thermal_bridge_width 0.5)
				(island_removal_mode 0)
			)
			(polygon
				(pts
					(xy 18.09242 -106.34472) (xy 18.09242 -105.83672) (xy 18.47342 -105.83672) (xy 18.47342 -106.34472)
				)
			)
		)
		(zone
			(layer "B.Cu")
			(hatch none 0.5)
			(connect_pads
				(clearance 0)
			)
			(min_thickness 0.25)
			(keepout
				(tracks not_allowed)
				(vias allowed)
				(pads allowed)
				(copperpour not_allowed)
				(footprints allowed)
			)
			(placement
				(enabled no)
				(sheetname "")
			)
			(fill
				(thermal_gap 0.5)
				(thermal_bridge_width 0.5)
				(island_removal_mode 0)
			)
			(polygon
				(pts
					(xy 18.47342 -106.34472) (xy 18.47342 -105.83672) (xy 18.09242 -105.83672) (xy 18.09242 -106.34472)
				)
			)
		)
	)
	(footprint ""
		(layer "B.Cu")
		(at 195.453 -144.977612 90)
		(property "Reference" "C6L6"
			(at 0 0 90)
			(layer "B.SilkS")
			(hide yes)
			(effects
				(font
					(size 1.27 1.27)
				)
				(justify mirror)
			)
		)
		(property "Value" ""
			(at 0 0 90)
			(layer "B.Fab")
			(effects
				(font
					(size 1.27 1.27)
				)
				(justify mirror)
			)
		)
		(duplicate_pad_numbers_are_jumpers no)
		(fp_poly
			(pts
				(xy -0.3048 -0.1016) (xy -0.3048 0.9906) (xy 0.3048 0.9906) (xy 0.3048 -0.1016)
			)
			(stroke
				(width 0)
				(type default)
			)
			(fill no)
			(layer "B.CrtYd")
		)
		(fp_line
			(start 0.3048 -0.1016)
			(end 0.3048 0.9906)
			(stroke
				(width 0.1)
				(type default)
			)
			(layer "B.Fab")
		)
		(fp_line
			(start -0.3048 -0.1016)
			(end 0.3048 -0.1016)
			(stroke
				(width 0.1)
				(type default)
			)
			(layer "B.Fab")
		)
		(fp_line
			(start 0.3048 0.9906)
			(end -0.3048 0.9906)
			(stroke
				(width 0.1)
				(type default)
			)
			(layer "B.Fab")
		)
		(fp_line
			(start -0.3048 0.9906)
			(end -0.3048 -0.1016)
			(stroke
				(width 0.1)
				(type default)
			)
			(layer "B.Fab")
		)
		(pad "1" smd rect
			(at 0 0 270)
			(size 0.508 0.508)
			(layers "B.Cu" "B.Mask" "B.Paste")
			(net "M_E_VREF")
		)
		(pad "2" smd rect
			(at 0 0.889 270)
			(size 0.508 0.508)
			(layers "B.Cu" "B.Mask" "B.Paste")
			(net "GND")
		)
		(zone
			(layer "B.Cu")
			(hatch none 0.5)
			(connect_pads
				(clearance 0)
			)
			(min_thickness 0.25)
			(keepout
				(tracks allowed)
				(vias not_allowed)
				(pads allowed)
				(copperpour not_allowed)
				(footprints allowed)
			)
			(placement
				(enabled no)
				(sheetname "")
			)
			(fill
				(thermal_gap 0.5)
				(thermal_bridge_width 0.5)
				(island_removal_mode 0)
			)
			(polygon
				(pts
					(xy 195.707 -145.231612) (xy 195.707 -144.723612) (xy 196.088 -144.723612) (xy 196.088 -145.231612)
				)
			)
		)
		(zone
			(layer "B.Cu")
			(hatch none 0.5)
			(connect_pads
				(clearance 0)
			)
			(min_thickness 0.25)
			(keepout
				(tracks not_allowed)
				(vias allowed)
				(pads allowed)
				(copperpour not_allowed)
				(footprints allowed)
			)
			(placement
				(enabled no)
				(sheetname "")
			)
			(fill
				(thermal_gap 0.5)
				(thermal_bridge_width 0.5)
				(island_removal_mode 0)
			)
			(polygon
				(pts
					(xy 196.088 -145.231612) (xy 196.088 -144.723612) (xy 195.707 -144.723612) (xy 195.707 -145.231612)
				)
			)
		)
	)
	(footprint ""
		(layer "B.Cu")
		(at 444.701168 -146.393662 180)
		(property "Reference" "U25W15"
			(at 0.14986 2.621788 180)
			(unlocked yes)
			(layer "B.SilkS")
			(effects
				(font
					(size 1.27 0.964946)
					(thickness 0.000001)
				)
				(justify left mirror)
			)
		)
		(property "Value" ""
			(at 0 0 0)
			(layer "B.Fab")
			(effects
				(font
					(size 1.27 1.27)
				)
				(justify mirror)
			)
		)
		(duplicate_pad_numbers_are_jumpers no)
		(fp_circle
			(center 0.4699 -0.8382)
			(end 0.3429 -0.8382)
			(stroke
				(width 0.254)
				(type default)
			)
			(fill no)
			(layer "B.SilkS")
		)
		(fp_poly
			(pts
				(xy -0.21463 -0.450088) (xy -1.56337 -0.450088) (xy -1.56337 1.75006) (xy -0.21463 1.75006)
			)
			(stroke
				(width 0)
				(type default)
			)
			(fill no)
			(layer "B.CrtYd")
		)
		(fp_line
			(start -0.21463 1.75006)
			(end -0.21463 -0.450088)
			(stroke
				(width 0.1)
				(type default)
			)
			(layer "B.Fab")
		)
		(fp_line
			(start -0.21463 -0.450088)
			(end -1.56337 -0.450088)
			(stroke
				(width 0.1)
				(type default)
			)
			(layer "B.Fab")
		)
		(fp_line
			(start -1.56337 1.75006)
			(end -0.21463 1.75006)
			(stroke
				(width 0.1)
				(type default)
			)
			(layer "B.Fab")
		)
		(fp_line
			(start -1.56337 -0.450088)
			(end -1.56337 1.75006)
			(stroke
				(width 0.1)
				(type default)
			)
			(layer "B.Fab")
		)
		(fp_circle
			(center 0.4699 -0.8382)
			(end 0.3429 -0.8382)
			(stroke
				(width 0.254)
				(type default)
			)
			(fill no)
			(layer "B.Fab")
		)
		(pad "1" smd rect
			(at 0 0)
			(size 1.016 0.381)
			(layers "B.Cu" "B.Mask" "B.Paste")
			(net "Net_6508")
		)
		(pad "2" smd rect
			(at 0 0.649986)
			(size 1.016 0.381)
			(layers "B.Cu" "B.Mask" "B.Paste")
			(net "BMC_DEBUG_EN_N")
		)
		(pad "3" smd rect
			(at 0 1.299972)
			(size 1.016 0.381)
			(layers "B.Cu" "B.Mask" "B.Paste")
			(net "GND")
		)
		(pad "4" smd rect
			(at -1.778 1.299972)
			(size 1.016 0.381)
			(layers "B.Cu" "B.Mask" "B.Paste")
			(net "CPU_XDP_PRESENT_N")
		)
		(pad "5" smd rect
			(at -1.778 0)
			(size 1.016 0.381)
			(layers "B.Cu" "B.Mask" "B.Paste")
			(net "P3V3_STBY")
		)
	)
	(footprint ""
		(layer "B.Cu")
		(at 481.3808 -113.1062 90)
		(property "Reference" "C1M24"
			(at 0 0 90)
			(layer "B.SilkS")
			(hide yes)
			(effects
				(font
					(size 1.27 1.27)
				)
				(justify mirror)
			)
		)
		(property "Value" ""
			(at 0 0 90)
			(layer "B.Fab")
			(effects
				(font
					(size 1.27 1.27)
				)
				(justify mirror)
			)
		)
		(duplicate_pad_numbers_are_jumpers no)
		(fp_rect
			(start 0.3048 0.9906)
			(end -0.3048 -0.1016)
			(stroke
				(width 0)
				(type default)
			)
			(fill no)
			(layer "B.CrtYd")
		)
		(fp_line
			(start 0.3048 -0.1016)
			(end 0.3048 0.9906)
			(stroke
				(width 0.1)
				(type default)
			)
			(layer "B.Fab")
		)
		(fp_line
			(start -0.3048 -0.1016)
			(end 0.3048 -0.1016)
			(stroke
				(width 0.1)
				(type default)
			)
			(layer "B.Fab")
		)
		(fp_line
			(start 0.3048 0.9906)
			(end -0.3048 0.9906)
			(stroke
				(width 0.1)
				(type default)
			)
			(layer "B.Fab")
		)
		(fp_line
			(start -0.3048 0.9906)
			(end -0.3048 -0.1016)
			(stroke
				(width 0.1)
				(type default)
			)
			(layer "B.Fab")
		)
		(pad "1" smd rect
			(at 0 0 270)
			(size 0.508 0.508)
			(layers "B.Cu" "B.Mask" "B.Paste")
			(net "P3V3")
		)
		(pad "2" smd rect
			(at 0 0.889 270)
			(size 0.508 0.508)
			(layers "B.Cu" "B.Mask" "B.Paste")
			(net "GND")
		)
		(zone
			(layer "B.Cu")
			(hatch none 0.5)
			(connect_pads
				(clearance 0)
			)
			(min_thickness 0.25)
			(keepout
				(tracks allowed)
				(vias not_allowed)
				(pads allowed)
				(copperpour not_allowed)
				(footprints allowed)
			)
			(placement
				(enabled no)
				(sheetname "")
			)
			(fill
				(thermal_gap 0.5)
				(thermal_bridge_width 0.5)
				(island_removal_mode 0)
			)
			(polygon
				(pts
					(xy 482.0158 -113.3602) (xy 481.6348 -113.3602) (xy 481.6348 -112.8522) (xy 482.0158 -112.8522)
				)
			)
		)
		(zone
			(layer "B.Cu")
			(hatch none 0.5)
			(connect_pads
				(clearance 0)
			)
			(min_thickness 0.25)
			(keepout
				(tracks not_allowed)
				(vias allowed)
				(pads allowed)
				(copperpour not_allowed)
				(footprints allowed)
			)
			(placement
				(enabled no)
				(sheetname "")
			)
			(fill
				(thermal_gap 0.5)
				(thermal_bridge_width 0.5)
				(island_removal_mode 0)
			)
			(polygon
				(pts
					(xy 482.0158 -113.3602) (xy 481.6348 -113.3602) (xy 481.6348 -112.8522) (xy 482.0158 -112.8522)
				)
			)
		)
	)
	(footprint ""
		(layer "B.Cu")
		(at 427.482 -42.0751 -90)
		(property "Reference" "FB2T5"
			(at 0 0 90)
			(layer "B.SilkS")
			(hide yes)
			(effects
				(font
					(size 1.27 1.27)
				)
				(justify mirror)
			)
		)
		(property "Value" "*"
			(at -0.0254 -2.8829 270)
			(unlocked yes)
			(layer "B.Fab")
			(hide yes)
			(effects
				(font
					(size 1.27 1.016)
					(thickness 0.1524)
				)
				(justify mirror)
			)
		)
		(property "Device Type" "HCB1608KF-800T30-GP_DISCRET-G9A"
			(at -0.0254 -4.4069 270)
			(unlocked yes)
			(layer "B.Fab")
			(hide yes)
			(effects
				(font
					(size 1.27 1.016)
					(thickness 0.1524)
				)
				(justify mirror)
			)
		)
		(duplicate_pad_numbers_are_jumpers no)
		(fp_line
			(start -0.254 0)
			(end 0.254 0)
			(stroke
				(width 0.2032)
				(type default)
			)
			(layer "B.SilkS")
		)
		(fp_rect
			(start 0.5842 1.3335)
			(end -0.5842 -1.3335)
			(stroke
				(width 0)
				(type default)
			)
			(fill no)
			(layer "B.CrtYd")
		)
		(fp_rect
			(start 0.5842 1.3335)
			(end -0.5842 -1.3335)
			(stroke
				(width 0)
				(type default)
			)
			(fill no)
			(layer "B.Fab")
		)
		(pad "1" smd custom
			(at 0 -0.762 90)
			(size 0.2159 0.2159)
			(layers "B.Cu" "B.Mask" "B.Paste")
			(net "P3V3_STBY")
			(options
				(clearance outline)
				(anchor circle)
			)
			(primitives
				(gr_poly
					(pts
						(arc
							(start -0.3302 0.4318)
							(mid -0.402042 0.402042)
							(end -0.4318 0.3302)
						)
						(arc
							(start -0.4318 -0.3302)
							(mid -0.402042 -0.402042)
							(end -0.3302 -0.4318)
						)
						(arc
							(start 0.3302 -0.4318)
							(mid 0.402042 -0.402042)
							(end 0.4318 -0.3302)
						)
						(arc
							(start 0.4318 0.3302)
							(mid 0.402042 0.402042)
							(end 0.3302 0.4318)
						)
					)
					(width 0)
					(fill yes)
				)
			)
		)
		(pad "2" smd custom
			(at 0 0.762 90)
			(size 0.2159 0.2159)
			(layers "B.Cu" "B.Mask" "B.Paste")
			(net "VCC_PA_3V3")
			(options
				(clearance outline)
				(anchor circle)
			)
			(primitives
				(gr_poly
					(pts
						(arc
							(start -0.3302 0.4318)
							(mid -0.402042 0.402042)
							(end -0.4318 0.3302)
						)
						(arc
							(start -0.4318 -0.3302)
							(mid -0.402042 -0.402042)
							(end -0.3302 -0.4318)
						)
						(arc
							(start 0.3302 -0.4318)
							(mid 0.402042 -0.402042)
							(end 0.4318 -0.3302)
						)
						(arc
							(start 0.4318 0.3302)
							(mid 0.402042 0.402042)
							(end 0.3302 0.4318)
						)
					)
					(width 0)
					(fill yes)
				)
			)
		)
	)
	(footprint ""
		(layer "B.Cu")
		(at 348.234 -83.5406)
		(property "Reference" "C3P4"
			(at 0 0 0)
			(layer "B.SilkS")
			(hide yes)
			(effects
				(font
					(size 1.27 1.27)
				)
				(justify mirror)
			)
		)
		(property "Value" ""
			(at 0 0 0)
			(layer "B.Fab")
			(effects
				(font
					(size 1.27 1.27)
				)
				(justify mirror)
			)
		)
		(duplicate_pad_numbers_are_jumpers no)
		(fp_poly
			(pts
				(xy -0.3048 -0.1016) (xy -0.3048 0.9906) (xy 0.3048 0.9906) (xy 0.3048 -0.1016)
			)
			(stroke
				(width 0)
				(type default)
			)
			(fill no)
			(layer "B.CrtYd")
		)
		(fp_line
			(start -0.3048 -0.1016)
			(end 0.3048 -0.1016)
			(stroke
				(width 0.1)
				(type default)
			)
			(layer "B.Fab")
		)
		(fp_line
			(start -0.3048 0.9906)
			(end -0.3048 -0.1016)
			(stroke
				(width 0.1)
				(type default)
			)
			(layer "B.Fab")
		)
		(fp_line
			(start 0.3048 -0.1016)
			(end 0.3048 0.9906)
			(stroke
				(width 0.1)
				(type default)
			)
			(layer "B.Fab")
		)
		(fp_line
			(start 0.3048 0.9906)
			(end -0.3048 0.9906)
			(stroke
				(width 0.1)
				(type default)
			)
			(layer "B.Fab")
		)
		(pad "1" smd rect
			(at 0 0 180)
			(size 0.508 0.508)
			(layers "B.Cu" "B.Mask" "B.Paste")
			(net "VR_PVCCIO_CPU0_VD12")
		)
		(pad "2" smd rect
			(at 0 0.889 180)
			(size 0.508 0.508)
			(layers "B.Cu" "B.Mask" "B.Paste")
			(net "GND")
		)
		(zone
			(layer "B.Cu")
			(hatch none 0.5)
			(connect_pads
				(clearance 0)
			)
			(min_thickness 0.25)
			(keepout
				(tracks allowed)
				(vias not_allowed)
				(pads allowed)
				(copperpour not_allowed)
				(footprints allowed)
			)
			(placement
				(enabled no)
				(sheetname "")
			)
			(fill
				(thermal_gap 0.5)
				(thermal_bridge_width 0.5)
				(island_removal_mode 0)
			)
			(polygon
				(pts
					(xy 348.488 -83.2866) (xy 347.98 -83.2866) (xy 347.98 -82.9056) (xy 348.488 -82.9056)
				)
			)
		)
		(zone
			(layer "B.Cu")
			(hatch none 0.5)
			(connect_pads
				(clearance 0)
			)
			(min_thickness 0.25)
			(keepout
				(tracks not_allowed)
				(vias allowed)
				(pads allowed)
				(copperpour not_allowed)
				(footprints allowed)
			)
			(placement
				(enabled no)
				(sheetname "")
			)
			(fill
				(thermal_gap 0.5)
				(thermal_bridge_width 0.5)
				(island_removal_mode 0)
			)
			(polygon
				(pts
					(xy 348.488 -82.9056) (xy 347.98 -82.9056) (xy 347.98 -83.2866) (xy 348.488 -83.2866)
				)
			)
		)
	)
)
